(kicad_pcb
	(version 20260206)
	(generator "pcbnew")
	(generator_version "10.0")
	(general
		(thickness 1.6)
		(legacy_teardrops no)
	)
	(paper "A4")
	(title_block
		(title "Bryce Canyon_R.DPB_16317-1_OCP.brd")
		(comment 1 "Bryce Canyon / footprints 1468-1475 of 2099")
	)
	(layers
		(0 "F.Cu" signal "TOP")
		(4 "In1.Cu" signal "L2GND")
		(6 "In2.Cu" signal "L3")
		(8 "In3.Cu" signal "L4VCC")
		(10 "In4.Cu" signal "L5VCC")
		(12 "In5.Cu" signal "L6")
		(14 "In6.Cu" signal "L7GND")
		(2 "B.Cu" signal "BOTTOM")
		(9 "F.Adhes" user "F.Adhesive")
		(11 "B.Adhes" user "B.Adhesive")
		(13 "F.Paste" user "Package Geometry/Pastemask Top")
		(15 "B.Paste" user "Package Geometry/Pastemask Bottom")
		(5 "F.SilkS" user "Ref Des/Silkscreen Top")
		(7 "B.SilkS" user "Ref Des/Silkscreen Bottom")
		(1 "F.Mask" user "Board Geometry/Soldermask Top")
		(3 "B.Mask" user "Board Geometry/Soldermask Bottom")
		(17 "Dwgs.User" user "User.Drawings")
		(19 "Cmts.User" user "User.Comments")
		(21 "Eco1.User" user "User.Eco1")
		(23 "Eco2.User" user "User.Eco2")
		(25 "Edge.Cuts" user "Board Geometry/Outline")
		(27 "Margin" user)
		(31 "F.CrtYd" user "Package Geometry/Place Bound Top")
		(29 "B.CrtYd" user "Package Geometry/Place Bound Bottom")
		(35 "F.Fab" user "Ref Des/Assembly Top")
		(33 "B.Fab" user "Ref Des/Assembly Bottom")
	)
	(footprint ""
		(layer "F.Cu")
		(at 249.69978 -211.19846)
		(property "Reference" "R114"
			(at 0 0 0)
			(layer "F.SilkS")
			(hide yes)
			(effects
				(font
					(size 1.27 1.27)
				)
			)
		)
		(property "Value" "10KR2F-2-GP"
			(at 0.064008 -3.993896 0)
			(unlocked yes)
			(layer "F.Fab")
			(hide yes)
			(effects
				(font
					(size 1.016 1.016)
					(thickness 0.1524)
				)
			)
		)
		(property "Device Type" "R402H16"
			(at 0.064008 -5.517896 0)
			(unlocked yes)
			(layer "F.Fab")
			(hide yes)
			(effects
				(font
					(size 1.016 1.016)
					(thickness 0.1524)
				)
			)
		)
		(duplicate_pad_numbers_are_jumpers no)
		(fp_line
			(start -0.508 -0.9398)
			(end -0.508 0.9398)
			(stroke
				(width 0.1524)
				(type default)
			)
			(layer "F.SilkS")
		)
		(fp_line
			(start 0.508 -0.9398)
			(end -0.508 -0.9398)
			(stroke
				(width 0.1524)
				(type default)
			)
			(layer "F.SilkS")
		)
		(fp_rect
			(start -0.508 0.9398)
			(end 0.508 -0.9398)
			(stroke
				(width 0)
				(type default)
			)
			(fill no)
			(layer "F.CrtYd")
		)
		(fp_rect
			(start -0.508 0.9398)
			(end 0.508 -0.9398)
			(stroke
				(width 0)
				(type default)
			)
			(fill no)
			(layer "F.Fab")
		)
		(pad "1" smd custom
			(at 0 -0.4445)
			(size 0.1397 0.1397)
			(layers "F.Cu" "F.Mask" "F.Paste")
			(net "EEPROM_WP")
			(options
				(clearance outline)
				(anchor circle)
			)
			(primitives
				(gr_poly
					(pts
						(arc
							(start -0.1778 -0.2794)
							(mid -0.249642 -0.249642)
							(end -0.2794 -0.1778)
						)
						(arc
							(start -0.2794 0.1778)
							(mid -0.249642 0.249642)
							(end -0.1778 0.2794)
						)
						(arc
							(start 0.1778 0.2794)
							(mid 0.249642 0.249642)
							(end 0.2794 0.1778)
						)
						(arc
							(start 0.2794 -0.1778)
							(mid 0.249642 -0.249642)
							(end 0.1778 -0.2794)
						)
					)
					(width 0)
					(fill yes)
				)
			)
		)
		(pad "2" smd custom
			(at 0 0.4445)
			(size 0.1397 0.1397)
			(layers "F.Cu" "F.Mask" "F.Paste")
			(net "GND")
			(options
				(clearance outline)
				(anchor circle)
			)
			(primitives
				(gr_poly
					(pts
						(arc
							(start -0.1778 -0.2794)
							(mid -0.249642 -0.249642)
							(end -0.2794 -0.1778)
						)
						(arc
							(start -0.2794 0.1778)
							(mid -0.249642 0.249642)
							(end -0.1778 0.2794)
						)
						(arc
							(start 0.1778 0.2794)
							(mid 0.249642 0.249642)
							(end 0.2794 0.1778)
						)
						(arc
							(start 0.2794 -0.1778)
							(mid 0.249642 -0.249642)
							(end 0.1778 -0.2794)
						)
					)
					(width 0)
					(fill yes)
				)
			)
		)
	)
	(footprint ""
		(layer "F.Cu")
		(at 465.140802 -231.52735)
		(property "Reference" "TP204"
			(at 0 0 0)
			(layer "F.SilkS")
			(hide yes)
			(effects
				(font
					(size 1.27 1.27)
				)
			)
		)
		(property "Value" "*"
			(at -0.0508 -1.6764 0)
			(unlocked yes)
			(layer "F.Fab")
			(hide yes)
			(effects
				(font
					(size 1.016 1.016)
					(thickness 0.1524)
				)
			)
		)
		(property "Device Type" "TPAD32"
			(at -0.0508 -3.2004 0)
			(unlocked yes)
			(layer "F.Fab")
			(hide yes)
			(effects
				(font
					(size 1.016 1.016)
					(thickness 0.1524)
				)
			)
		)
		(duplicate_pad_numbers_are_jumpers no)
		(fp_poly
			(pts
				(arc
					(start 0.4064 0)
					(mid -0.4064 0)
					(end 0.4064 0)
				)
			)
			(stroke
				(width 0)
				(type default)
			)
			(fill no)
			(layer "F.CrtYd")
		)
		(fp_poly
			(pts
				(arc
					(start 0.7112 0)
					(mid -0.7112 0)
					(end 0.7112 0)
				)
			)
			(stroke
				(width 0)
				(type default)
			)
			(fill no)
			(layer "F.Fab")
		)
		(pad "1" smd circle
			(at 0 0)
			(size 0.8128 0.8128)
			(layers "F.Cu" "F.Mask" "F.Paste")
			(net "P5V_B_3_PGOOD")
		)
	)
	(footprint ""
		(layer "F.Cu")
		(at 258.474972 -372.32971)
		(property "Reference" "R1037"
			(at 0 0 0)
			(layer "F.SilkS")
			(hide yes)
			(effects
				(font
					(size 1.27 1.27)
				)
			)
		)
		(property "Value" "10KR2F-2-GP"
			(at 0.064008 -3.993896 0)
			(unlocked yes)
			(layer "F.Fab")
			(hide yes)
			(effects
				(font
					(size 1.016 1.016)
					(thickness 0.1524)
				)
			)
		)
		(property "Device Type" "R402H16"
			(at 0.064008 -5.517896 0)
			(unlocked yes)
			(layer "F.Fab")
			(hide yes)
			(effects
				(font
					(size 1.016 1.016)
					(thickness 0.1524)
				)
			)
		)
		(duplicate_pad_numbers_are_jumpers no)
		(fp_line
			(start -0.508 -0.9398)
			(end -0.508 0.9398)
			(stroke
				(width 0.1524)
				(type default)
			)
			(layer "F.SilkS")
		)
		(fp_line
			(start 0.508 -0.9398)
			(end -0.508 -0.9398)
			(stroke
				(width 0.1524)
				(type default)
			)
			(layer "F.SilkS")
		)
		(fp_rect
			(start -0.508 0.9398)
			(end 0.508 -0.9398)
			(stroke
				(width 0)
				(type default)
			)
			(fill no)
			(layer "F.CrtYd")
		)
		(fp_rect
			(start -0.508 0.9398)
			(end 0.508 -0.9398)
			(stroke
				(width 0)
				(type default)
			)
			(fill no)
			(layer "F.Fab")
		)
		(pad "1" smd custom
			(at 0 -0.4445)
			(size 0.1397 0.1397)
			(layers "F.Cu" "F.Mask" "F.Paste")
			(net "P12V_B")
			(options
				(clearance outline)
				(anchor circle)
			)
			(primitives
				(gr_poly
					(pts
						(arc
							(start -0.1778 -0.2794)
							(mid -0.249642 -0.249642)
							(end -0.2794 -0.1778)
						)
						(arc
							(start -0.2794 0.1778)
							(mid -0.249642 0.249642)
							(end -0.1778 0.2794)
						)
						(arc
							(start 0.1778 0.2794)
							(mid 0.249642 0.249642)
							(end 0.2794 0.1778)
						)
						(arc
							(start 0.2794 -0.1778)
							(mid 0.249642 -0.249642)
							(end 0.1778 -0.2794)
						)
					)
					(width 0)
					(fill yes)
				)
			)
		)
		(pad "2" smd custom
			(at 0 0.4445)
			(size 0.1397 0.1397)
			(layers "F.Cu" "F.Mask" "F.Paste")
			(net "P12V_B_PGOOD")
			(options
				(clearance outline)
				(anchor circle)
			)
			(primitives
				(gr_poly
					(pts
						(arc
							(start -0.1778 -0.2794)
							(mid -0.249642 -0.249642)
							(end -0.2794 -0.1778)
						)
						(arc
							(start -0.2794 0.1778)
							(mid -0.249642 0.249642)
							(end -0.1778 0.2794)
						)
						(arc
							(start 0.1778 0.2794)
							(mid 0.249642 0.249642)
							(end 0.2794 0.1778)
						)
						(arc
							(start 0.2794 -0.1778)
							(mid 0.249642 -0.249642)
							(end 0.1778 -0.2794)
						)
					)
					(width 0)
					(fill yes)
				)
			)
		)
	)
	(footprint ""
		(layer "F.Cu")
		(at 32.508952 -133.75005 -90)
		(property "Reference" "VIA26"
			(at 0 0 270)
			(layer "F.SilkS")
			(hide yes)
			(effects
				(font
					(size 1.27 1.27)
				)
			)
		)
		(property "Value" "100OHM-8L-2D36MM-L16-GP"
			(at -3.4036 -0.4572 270)
			(unlocked yes)
			(layer "F.Fab")
			(hide yes)
			(effects
				(font
					(size 1.016 1.016)
					(thickness 0.1524)
				)
			)
		)
		(property "Device Type" "VIA-PCIE-4P-427097"
			(at -3.4036 -1.9812 270)
			(unlocked yes)
			(layer "F.Fab")
			(hide yes)
			(effects
				(font
					(size 1.016 1.016)
					(thickness 0.1524)
				)
			)
		)
		(duplicate_pad_numbers_are_jumpers no)
		(fp_rect
			(start -2.1336 0.4826)
			(end 2.1336 -0.4826)
			(stroke
				(width 0)
				(type default)
			)
			(fill no)
			(layer "F.CrtYd")
		)
		(fp_rect
			(start -2.1336 0.4826)
			(end 2.1336 -0.4826)
			(stroke
				(width 0)
				(type default)
			)
			(fill no)
			(layer "F.Fab")
		)
		(pad "1" thru_hole circle
			(at -1.651 0 270)
			(size 0.508 0.508)
			(drill 0.254)
			(layers "*.Cu" "*.Mask")
			(remove_unused_layers no)
			(net "GND")
			(clearance 0.2286)
			(thermal_gap 0.2286)
		)
		(pad "2" thru_hole circle
			(at -0.635 0 270)
			(size 0.508 0.508)
			(drill 0.254)
			(layers "*.Cu" "*.Mask")
			(remove_unused_layers no)
			(net "PHY_DRV_B_TO_SCC_B_12_DP")
			(clearance 0.2286)
			(thermal_gap 0.2286)
		)
		(pad "3" thru_hole circle
			(at 0.635 0 270)
			(size 0.508 0.508)
			(drill 0.254)
			(layers "*.Cu" "*.Mask")
			(remove_unused_layers no)
			(net "PHY_DRV_B_TO_SCC_B_12_DN")
			(clearance 0.2286)
			(thermal_gap 0.2286)
		)
		(pad "4" thru_hole circle
			(at 1.651 0 270)
			(size 0.508 0.508)
			(drill 0.254)
			(layers "*.Cu" "*.Mask")
			(remove_unused_layers no)
			(net "GND")
			(clearance 0.2286)
			(thermal_gap 0.2286)
		)
	)
	(footprint ""
		(layer "F.Cu")
		(at 96.324928 -293.799768)
		(property "Reference" ""
			(at 0 0 0)
			(layer "F.SilkS")
			(hide yes)
			(effects
				(font
					(size 1.27 1.27)
				)
			)
		)
		(property "Value" "*"
			(at -8.398764 -8.057642 0)
			(unlocked yes)
			(layer "F.Fab")
			(hide yes)
			(effects
				(font
					(size 1.016 1.016)
					(thickness 0.1524)
				)
			)
		)
		(duplicate_pad_numbers_are_jumpers no)
		(fp_poly
			(pts
				(arc
					(start 7.3152 0)
					(mid 0 7.3152)
					(end -7.3152 0)
				)
				(arc
					(start -7.3152 -5.9944)
					(mid 0 -13.3096)
					(end 7.3152 -5.9944)
				)
			)
			(stroke
				(width 0)
				(type default)
			)
			(fill no)
			(layer "B.CrtYd")
		)
		(fp_poly
			(pts
				(arc
					(start 7.3152 0)
					(mid 0 7.3152)
					(end -7.3152 0)
				)
				(arc
					(start -7.3152 -5.9944)
					(mid 0 -13.3096)
					(end 7.3152 -5.9944)
				)
			)
			(stroke
				(width 0)
				(type default)
			)
			(fill no)
			(layer "F.CrtYd")
		)
		(fp_poly
			(pts
				(arc
					(start 7.3152 0)
					(mid 0 7.3152)
					(end -7.3152 0)
				)
				(arc
					(start -7.3152 -5.9944)
					(mid 0 -13.3096)
					(end 7.3152 -5.9944)
				)
			)
			(stroke
				(width 0)
				(type default)
			)
			(fill no)
			(layer "B.Fab")
		)
		(fp_poly
			(pts
				(arc
					(start 7.3152 0)
					(mid 0 7.3152)
					(end -7.3152 0)
				)
				(arc
					(start -7.3152 -5.9944)
					(mid 0 -13.3096)
					(end 7.3152 -5.9944)
				)
			)
			(stroke
				(width 0)
				(type default)
			)
			(fill no)
			(layer "F.Fab")
		)
		(pad "1" thru_hole oval
			(at 0 0)
			(size 14.0208 20.0152)
			(drill 0.0254
				(offset 0 -2.9972)
			)
			(layers "*.Cu" "*.Mask")
			(remove_unused_layers no)
			(net "Net_38")
			(clearance -1.002284)
			(thermal_gap 0.1524)
			(padstack
				(mode front_inner_back)
				(layer "Inner"
					(shape custom)
					(size 2.928012 2.928012)
					(options
						(anchor circle)
					)
					(primitives
						(gr_poly
							(pts
								(arc
									(start 4.571746 -2.084324)
									(mid 0.000333 7.430372)
									(end -4.571492 -2.084324)
								)
								(arc
									(start -4.571492 -2.084324)
									(mid -3.570296 -3.611977)
									(end -2.875026 -5.30098)
								)
								(arc
									(start -2.875026 -5.30098)
									(mid 0.000217 -7.43089)
									(end 2.87528 -5.30098)
								)
								(arc
									(start 2.87528 -5.30098)
									(mid 3.570511 -3.611956)
									(end 4.571746 -2.084324)
								)
							)
							(width 0)
							(fill yes)
						)
					)
					(clearance 0.1524)
				)
				(layer "B.Cu"
					(shape oval)
					(size 14.0208 20.0152)
					(offset 0 -2.9972)
					(clearance -1.002284)
				)
			)
		)
		(zone
			(layers "F.Cu" "B.Cu" "In1.Cu" "In2.Cu" "In3.Cu" "In4.Cu" "In5.Cu" "In6.Cu")
			(hatch none 0.5)
			(connect_pads
				(clearance 0)
			)
			(min_thickness 0.25)
			(keepout
				(tracks not_allowed)
				(vias allowed)
				(pads allowed)
				(copperpour not_allowed)
				(footprints allowed)
			)
			(placement
				(enabled no)
				(sheetname "")
			)
			(fill
				(thermal_gap 0.5)
				(thermal_bridge_width 0.5)
				(island_removal_mode 0)
			)
			(polygon
				(pts
					(arc
						(start 89.314528 -299.794168)
						(mid 96.324928 -306.804568)
						(end 103.335328 -299.794168)
					)
					(arc
						(start 103.335328 -293.799768)
						(mid 96.324928 -286.789368)
						(end 89.314528 -293.799768)
					)
				)
			)
		)
	)
	(footprint ""
		(layer "F.Cu")
		(at 95.563436 -245.219474 90)
		(property "Reference" "C54"
			(at 0 0 90)
			(layer "F.SilkS")
			(hide yes)
			(effects
				(font
					(size 1.27 1.27)
				)
			)
		)
		(property "Value" "SCD01U16V1KX-GP"
			(at -2.8321 -1.7399 90)
			(unlocked yes)
			(layer "F.Fab")
			(hide yes)
			(effects
				(font
					(size 1.016 1.016)
					(thickness 0.1524)
				)
			)
		)
		(property "Device Type" "C0201H13"
			(at -2.8321 -3.2639 90)
			(unlocked yes)
			(layer "F.Fab")
			(hide yes)
			(effects
				(font
					(size 1.016 1.016)
					(thickness 0.1524)
				)
			)
		)
		(duplicate_pad_numbers_are_jumpers no)
		(fp_rect
			(start -0.2794 0.6477)
			(end 0.2794 -0.6477)
			(stroke
				(width 0)
				(type default)
			)
			(fill no)
			(layer "F.CrtYd")
		)
		(fp_rect
			(start -0.2794 0.6477)
			(end 0.2794 -0.6477)
			(stroke
				(width 0)
				(type default)
			)
			(fill no)
			(layer "F.Fab")
		)
		(pad "1" smd custom
			(at 0 -0.2794 90)
			(size 0.0762 0.0762)
			(layers "F.Cu" "F.Mask" "F.Paste")
			(net "SAS_HDD_RX_N2")
			(options
				(clearance outline)
				(anchor circle)
			)
			(primitives
				(gr_poly
					(pts
						(arc
							(start 0.1524 -0.127)
							(mid 0.137521 -0.162921)
							(end 0.1016 -0.1778)
						)
						(arc
							(start -0.1016 -0.1778)
							(mid -0.137521 -0.162921)
							(end -0.1524 -0.127)
						)
						(arc
							(start -0.1524 0.127)
							(mid -0.137521 0.162921)
							(end -0.1016 0.1778)
						)
						(arc
							(start 0.1016 0.1778)
							(mid 0.137521 0.162921)
							(end 0.1524 0.127)
						)
					)
					(width 0)
					(fill yes)
				)
			)
		)
		(pad "2" smd custom
			(at 0 0.2794 90)
			(size 0.0762 0.0762)
			(layers "F.Cu" "F.Mask" "F.Paste")
			(net "PHY_SCC_B_TO_DRV_B_2_DN")
			(options
				(clearance outline)
				(anchor circle)
			)
			(primitives
				(gr_poly
					(pts
						(arc
							(start 0.1524 -0.127)
							(mid 0.137521 -0.162921)
							(end 0.1016 -0.1778)
						)
						(arc
							(start -0.1016 -0.1778)
							(mid -0.137521 -0.162921)
							(end -0.1524 -0.127)
						)
						(arc
							(start -0.1524 0.127)
							(mid -0.137521 0.162921)
							(end -0.1016 0.1778)
						)
						(arc
							(start 0.1016 0.1778)
							(mid 0.137521 0.162921)
							(end 0.1524 0.127)
						)
					)
					(width 0)
					(fill yes)
				)
			)
		)
	)
	(footprint ""
		(layer "F.Cu")
		(at 16.764 -23.114 90)
		(property "Reference" "R629"
			(at 0 0 90)
			(layer "F.SilkS")
			(hide yes)
			(effects
				(font
					(size 1.27 1.27)
				)
			)
		)
		(property "Value" "4K7R2J-2-GP"
			(at 0.064008 -3.993896 90)
			(unlocked yes)
			(layer "F.Fab")
			(hide yes)
			(effects
				(font
					(size 1.016 1.016)
					(thickness 0.1524)
				)
			)
		)
		(property "Device Type" "R402H16"
			(at 0.064008 -5.517896 90)
			(unlocked yes)
			(layer "F.Fab")
			(hide yes)
			(effects
				(font
					(size 1.016 1.016)
					(thickness 0.1524)
				)
			)
		)
		(duplicate_pad_numbers_are_jumpers no)
		(fp_line
			(start 0.508 -0.9398)
			(end -0.508 -0.9398)
			(stroke
				(width 0.1524)
				(type default)
			)
			(layer "F.SilkS")
		)
		(fp_line
			(start -0.508 -0.9398)
			(end -0.508 0.9398)
			(stroke
				(width 0.1524)
				(type default)
			)
			(layer "F.SilkS")
		)
		(fp_rect
			(start -0.508 0.9398)
			(end 0.508 -0.9398)
			(stroke
				(width 0)
				(type default)
			)
			(fill no)
			(layer "F.CrtYd")
		)
		(fp_rect
			(start -0.508 0.9398)
			(end 0.508 -0.9398)
			(stroke
				(width 0)
				(type default)
			)
			(fill no)
			(layer "F.Fab")
		)
		(pad "1" smd custom
			(at 0 -0.4445 90)
			(size 0.1397 0.1397)
			(layers "F.Cu" "F.Mask" "F.Paste")
			(net "P12V_B")
			(options
				(clearance outline)
				(anchor circle)
			)
			(primitives
				(gr_poly
					(pts
						(arc
							(start -0.1778 -0.2794)
							(mid -0.249642 -0.249642)
							(end -0.2794 -0.1778)
						)
						(arc
							(start -0.2794 0.1778)
							(mid -0.249642 0.249642)
							(end -0.1778 0.2794)
						)
						(arc
							(start 0.1778 0.2794)
							(mid 0.249642 0.249642)
							(end 0.2794 0.1778)
						)
						(arc
							(start 0.2794 -0.1778)
							(mid 0.249642 -0.249642)
							(end 0.1778 -0.2794)
						)
					)
					(width 0)
					(fill yes)
				)
			)
		)
		(pad "2" smd custom
			(at 0 0.4445 90)
			(size 0.1397 0.1397)
			(layers "F.Cu" "F.Mask" "F.Paste")
			(net "SW_HDD_P24")
			(options
				(clearance outline)
				(anchor circle)
			)
			(primitives
				(gr_poly
					(pts
						(arc
							(start -0.1778 -0.2794)
							(mid -0.249642 -0.249642)
							(end -0.2794 -0.1778)
						)
						(arc
							(start -0.2794 0.1778)
							(mid -0.249642 0.249642)
							(end -0.1778 0.2794)
						)
						(arc
							(start 0.1778 0.2794)
							(mid 0.249642 0.249642)
							(end 0.2794 0.1778)
						)
						(arc
							(start 0.2794 -0.1778)
							(mid 0.249642 -0.249642)
							(end 0.1778 -0.2794)
						)
					)
					(width 0)
					(fill yes)
				)
			)
		)
	)
	(footprint ""
		(layer "F.Cu")
		(at 331.089 -10.16)
		(property "Reference" "R773"
			(at 0 0 0)
			(layer "F.SilkS")
			(hide yes)
			(effects
				(font
					(size 1.27 1.27)
				)
			)
		)
		(property "Value" "4K7R2F-GP"
			(at 0.064008 -3.993896 0)
			(unlocked yes)
			(layer "F.Fab")
			(hide yes)
			(effects
				(font
					(size 1.016 1.016)
					(thickness 0.1524)
				)
			)
		)
		(property "Device Type" "R402H16"
			(at 0.064008 -5.517896 0)
			(unlocked yes)
			(layer "F.Fab")
			(hide yes)
			(effects
				(font
					(size 1.016 1.016)
					(thickness 0.1524)
				)
			)
		)
		(duplicate_pad_numbers_are_jumpers no)
		(fp_line
			(start -0.508 -0.9398)
			(end -0.508 0.9398)
			(stroke
				(width 0.1524)
				(type default)
			)
			(layer "F.SilkS")
		)
		(fp_line
			(start 0.508 -0.9398)
			(end -0.508 -0.9398)
			(stroke
				(width 0.1524)
				(type default)
			)
			(layer "F.SilkS")
		)
		(fp_rect
			(start -0.508 0.9398)
			(end 0.508 -0.9398)
			(stroke
				(width 0)
				(type default)
			)
			(fill no)
			(layer "F.CrtYd")
		)
		(fp_rect
			(start -0.508 0.9398)
			(end 0.508 -0.9398)
			(stroke
				(width 0)
				(type default)
			)
			(fill no)
			(layer "F.Fab")
		)
		(pad "1" smd custom
			(at 0 -0.4445)
			(size 0.1397 0.1397)
			(layers "F.Cu" "F.Mask" "F.Paste")
			(net "SW_PWR_R_HDD30")
			(options
				(clearance outline)
				(anchor circle)
			)
			(primitives
				(gr_poly
					(pts
						(arc
							(start -0.1778 -0.2794)
							(mid -0.249642 -0.249642)
							(end -0.2794 -0.1778)
						)
						(arc
							(start -0.2794 0.1778)
							(mid -0.249642 0.249642)
							(end -0.1778 0.2794)
						)
						(arc
							(start 0.1778 0.2794)
							(mid 0.249642 0.249642)
							(end 0.2794 0.1778)
						)
						(arc
							(start 0.2794 -0.1778)
							(mid 0.249642 -0.249642)
							(end 0.1778 -0.2794)
						)
					)
					(width 0)
					(fill yes)
				)
			)
		)
		(pad "2" smd custom
			(at 0 0.4445)
			(size 0.1397 0.1397)
			(layers "F.Cu" "F.Mask" "F.Paste")
			(net "GND")
			(options
				(clearance outline)
				(anchor circle)
			)
			(primitives
				(gr_poly
					(pts
						(arc
							(start -0.1778 -0.2794)
							(mid -0.249642 -0.249642)
							(end -0.2794 -0.1778)
						)
						(arc
							(start -0.2794 0.1778)
							(mid -0.249642 0.249642)
							(end -0.1778 0.2794)
						)
						(arc
							(start 0.1778 0.2794)
							(mid 0.249642 0.249642)
							(end 0.2794 0.1778)
						)
						(arc
							(start 0.2794 -0.1778)
							(mid 0.249642 -0.249642)
							(end 0.1778 -0.2794)
						)
					)
					(width 0)
					(fill yes)
				)
			)
		)
	)
)
